# S9S_MB_2U (Grand Teton) — schematic netlist excerpt (pin names and nets, part order shuffled) for the footprints in the layout excerpt that follows; sources: Cadence DE-HDL packaged netlist, KiCad conversion of 03242023_DA0F0TMBIJ0_F0T_Motherboard_J_brd_V01_OCP.brd

PC1211_P0_1  Q_CAP  2.2UF 10V 10% X6S  pkg C0402  page 271 : A = PVCCFA_EHV_FIVRA_CPU0_PVCC1 ; B = GND
R853  Q_RES  0 5% CHIP  pkg 0402LF  page 128 : A = RST_CPU0_DRAM_EF_N ; B = RST_CPU0_DRAM_EF_PLD_N

(kicad_pcb
	(version 20260206)
	(generator "pcbnew")
	(generator_version "10.0")
	(general
		(thickness 1.6)
		(legacy_teardrops no)
	)
	(paper "A4")
	(title_block
		(title "03242023_DA0F0TMBIJ0_F0T_Motherboard_J_brd_V01_OCP.brd")
		(comment 1 "Grand Teton / footprints 2624-2625 of 6105")
	)
	(layers
		(0 "F.Cu" signal "TOP")
		(4 "In1.Cu" signal "GND")
		(6 "In2.Cu" signal "IN1")
		(8 "In3.Cu" signal "GND1")
		(10 "In4.Cu" signal "IN2")
		(12 "In5.Cu" signal "GND2")
		(14 "In6.Cu" signal "IN3")
		(16 "In7.Cu" signal "GND3")
		(18 "In8.Cu" signal "VCC")
		(20 "In9.Cu" signal "VCC1")
		(22 "In10.Cu" signal "GND4")
		(24 "In11.Cu" signal "IN4")
		(26 "In12.Cu" signal "GND5")
		(28 "In13.Cu" signal "IN5")
		(30 "In14.Cu" signal "GND6")
		(32 "In15.Cu" signal "IN6")
		(34 "In16.Cu" signal "GND7")
		(2 "B.Cu" signal "BOTTOM")
		(9 "F.Adhes" user "F.Adhesive")
		(11 "B.Adhes" user "B.Adhesive")
		(13 "F.Paste" user "Package Geometry/Pastemask Top")
		(15 "B.Paste" user "Package Geometry/Pastemask Bottom")
		(5 "F.SilkS" user "Ref Des/Silkscreen Top")
		(7 "B.SilkS" user "Ref Des/Silkscreen Bottom")
		(1 "F.Mask" user "Board Geometry/Soldermask Top")
		(3 "B.Mask" user "Board Geometry/Soldermask Bottom")
		(17 "Dwgs.User" user "User.Drawings")
		(19 "Cmts.User" user "User.Comments")
		(21 "Eco1.User" user "User.Eco1")
		(23 "Eco2.User" user "User.Eco2")
		(25 "Edge.Cuts" user "Board Geometry/Outline")
		(27 "Margin" user)
		(31 "F.CrtYd" user "Package Geometry/Place Bound Top")
		(29 "B.CrtYd" user "Package Geometry/Place Bound Bottom")
		(35 "F.Fab" user "Ref Des/Assembly Top")
		(33 "B.Fab" user "Ref Des/Assembly Bottom")
	)
	(footprint ""
		(layer "F.Cu")
		(at 115.95608 -119.846598 -90)
		(property "Reference" "R853"
			(at 0 0 270)
			(layer "F.SilkS")
			(hide yes)
			(effects
				(font
					(size 1.27 1.27)
				)
			)
		)
		(property "Value" ""
			(at 0 0 270)
			(layer "F.Fab")
			(effects
				(font
					(size 1.27 1.27)
				)
			)
		)
		(duplicate_pad_numbers_are_jumpers no)
		(fp_line
			(start -0.7874 0.4064)
			(end -0.7874 -0.4064)
			(stroke
				(width 0.1524)
				(type default)
			)
			(layer "F.SilkS")
		)
		(fp_line
			(start 0.7874 0.4064)
			(end -0.7874 0.4064)
			(stroke
				(width 0.1524)
				(type default)
			)
			(layer "F.SilkS")
		)
		(fp_line
			(start -0.7874 -0.4064)
			(end 0.7874 -0.4064)
			(stroke
				(width 0.1524)
				(type default)
			)
			(layer "F.SilkS")
		)
		(fp_line
			(start 0.7874 -0.4064)
			(end 0.7874 0.4064)
			(stroke
				(width 0.1524)
				(type default)
			)
			(layer "F.SilkS")
		)
		(fp_line
			(start -0.67945 0.3048)
			(end -0.67945 -0.305054)
			(stroke
				(width 0.1)
				(type default)
			)
			(layer "F.Fab")
		)
		(fp_line
			(start -0.12065 0.3048)
			(end -0.67945 0.3048)
			(stroke
				(width 0.1)
				(type default)
			)
			(layer "F.Fab")
		)
		(fp_line
			(start 0.120396 0.3048)
			(end 0.120396 0.2794)
			(stroke
				(width 0.1)
				(type default)
			)
			(layer "F.Fab")
		)
		(fp_line
			(start 0.67945 0.3048)
			(end 0.120396 0.3048)
			(stroke
				(width 0.1)
				(type default)
			)
			(layer "F.Fab")
		)
		(fp_line
			(start -0.12065 0.2794)
			(end -0.12065 0.3048)
			(stroke
				(width 0.1)
				(type default)
			)
			(layer "F.Fab")
		)
		(fp_line
			(start 0.120396 0.2794)
			(end -0.12065 0.2794)
			(stroke
				(width 0.1)
				(type default)
			)
			(layer "F.Fab")
		)
		(fp_line
			(start -0.12065 -0.2794)
			(end 0.12065 -0.2794)
			(stroke
				(width 0.1)
				(type default)
			)
			(layer "F.Fab")
		)
		(fp_line
			(start 0.12065 -0.2794)
			(end 0.12065 -0.3048)
			(stroke
				(width 0.1)
				(type default)
			)
			(layer "F.Fab")
		)
		(fp_line
			(start 0.12065 -0.3048)
			(end 0.67945 -0.3048)
			(stroke
				(width 0.1)
				(type default)
			)
			(layer "F.Fab")
		)
		(fp_line
			(start 0.67945 -0.3048)
			(end 0.67945 0.3048)
			(stroke
				(width 0.1)
				(type default)
			)
			(layer "F.Fab")
		)
		(fp_line
			(start -0.67945 -0.305054)
			(end -0.12065 -0.305054)
			(stroke
				(width 0.1)
				(type default)
			)
			(layer "F.Fab")
		)
		(fp_line
			(start -0.12065 -0.305054)
			(end -0.12065 -0.2794)
			(stroke
				(width 0.1)
				(type default)
			)
			(layer "F.Fab")
		)
		(pad "1" smd circle
			(at -0.40005 0 270)
			(size 0 0)
			(layers "F.Cu" "F.Mask" "F.Paste")
			(net "RST_CPU0_DRAM_EF_N")
		)
		(pad "2" smd circle
			(at 0.40005 0 270)
			(size 0 0)
			(layers "F.Cu" "F.Mask" "F.Paste")
			(net "RST_CPU0_DRAM_EF_PLD_N")
		)
	)
	(footprint ""
		(layer "F.Cu")
		(at 412.585662 -361.896914 -90)
		(property "Reference" "PC1211_P0_1"
			(at 0 0 270)
			(layer "F.SilkS")
			(hide yes)
			(effects
				(font
					(size 1.27 1.27)
				)
			)
		)
		(property "Value" ""
			(at 0 0 270)
			(layer "F.Fab")
			(effects
				(font
					(size 1.27 1.27)
				)
			)
		)
		(duplicate_pad_numbers_are_jumpers no)
		(fp_line
			(start -0.7874 0.4064)
			(end -0.7874 -0.4064)
			(stroke
				(width 0.1524)
				(type default)
			)
			(layer "F.SilkS")
		)
		(fp_line
			(start 0.7874 0.4064)
			(end -0.7874 0.4064)
			(stroke
				(width 0.1524)
				(type default)
			)
			(layer "F.SilkS")
		)
		(fp_line
			(start -0.7874 -0.4064)
			(end 0.7874 -0.4064)
			(stroke
				(width 0.1524)
				(type default)
			)
			(layer "F.SilkS")
		)
		(fp_line
			(start 0.7874 -0.4064)
			(end 0.7874 0.4064)
			(stroke
				(width 0.1524)
				(type default)
			)
			(layer "F.SilkS")
		)
		(fp_line
			(start -0.67945 0.3048)
			(end -0.67945 -0.305054)
			(stroke
				(width 0.1)
				(type default)
			)
			(layer "F.Fab")
		)
		(fp_line
			(start -0.12065 0.3048)
			(end -0.67945 0.3048)
			(stroke
				(width 0.1)
				(type default)
			)
			(layer "F.Fab")
		)
		(fp_line
			(start 0.120396 0.3048)
			(end 0.120396 0.2794)
			(stroke
				(width 0.1)
				(type default)
			)
			(layer "F.Fab")
		)
		(fp_line
			(start 0.67945 0.3048)
			(end 0.120396 0.3048)
			(stroke
				(width 0.1)
				(type default)
			)
			(layer "F.Fab")
		)
		(fp_line
			(start -0.12065 0.2794)
			(end -0.12065 0.3048)
			(stroke
				(width 0.1)
				(type default)
			)
			(layer "F.Fab")
		)
		(fp_line
			(start 0.120396 0.2794)
			(end -0.12065 0.2794)
			(stroke
				(width 0.1)
				(type default)
			)
			(layer "F.Fab")
		)
		(fp_line
			(start -0.12065 -0.2794)
			(end 0.12065 -0.2794)
			(stroke
				(width 0.1)
				(type default)
			)
			(layer "F.Fab")
		)
		(fp_line
			(start 0.12065 -0.2794)
			(end 0.12065 -0.3048)
			(stroke
				(width 0.1)
				(type default)
			)
			(layer "F.Fab")
		)
		(fp_line
			(start 0.12065 -0.3048)
			(end 0.67945 -0.3048)
			(stroke
				(width 0.1)
				(type default)
			)
			(layer "F.Fab")
		)
		(fp_line
			(start 0.67945 -0.3048)
			(end 0.67945 0.3048)
			(stroke
				(width 0.1)
				(type default)
			)
			(layer "F.Fab")
		)
		(fp_line
			(start -0.67945 -0.305054)
			(end -0.12065 -0.305054)
			(stroke
				(width 0.1)
				(type default)
			)
			(layer "F.Fab")
		)
		(fp_line
			(start -0.12065 -0.305054)
			(end -0.12065 -0.2794)
			(stroke
				(width 0.1)
				(type default)
			)
			(layer "F.Fab")
		)
		(pad "1" smd circle
			(at -0.40005 0 270)
			(size 0 0)
			(layers "F.Cu" "F.Mask" "F.Paste")
			(net "PVCCFA_EHV_FIVRA_CPU0_PVCC1")
		)
		(pad "2" smd circle
			(at 0.40005 0 270)
			(size 0 0)
			(layers "F.Cu" "F.Mask" "F.Paste")
			(net "GND")
		)
	)
)
